# TIMECARD (Time Appliance Project (Time Card)) — schematic netlist excerpt (pin names and nets, part order shuffled) for the footprints in the layout excerpt that follows; sources: Cadence DE-HDL packaged netlist, KiCad conversion of R4006-B0001-02_R01.brd

R2  RESISTOR  330OHM 1%  pkg SMC_0402R_H016  page 16 : \1\ = FPGA_OUT_SEC_EEPROM_WP ; \2\ = SEC_EEPROM_WP
R37  RESISTOR  0OHM -  pkg SMC_0402R_H016  page 28 : \1\ = XP3R3V_BT ; \2\ = UNNAMED_517_CAPACITOR_I27_1

(kicad_pcb
	(version 20260206)
	(generator "pcbnew")
	(generator_version "10.0")
	(general
		(thickness 1.6)
		(legacy_teardrops no)
	)
	(paper "A4")
	(title_block
		(title "timecard-production-celestica-r4006 — R4006-B0001-02_R01.brd")
		(comment 1 "Time Appliance Project (Time Card) / footprints 1053-1054 of 1113")
	)
	(layers
		(0 "F.Cu" signal "TOP")
		(4 "In1.Cu" signal "L02_GND1")
		(6 "In2.Cu" signal "L03_SIG1")
		(8 "In3.Cu" signal "L04_GND2")
		(10 "In4.Cu" signal "L05_VCC1")
		(12 "In5.Cu" signal "L06_VCC2")
		(14 "In6.Cu" signal "L07_GND3")
		(16 "In7.Cu" signal "L08_SIG2")
		(18 "In8.Cu" signal "L09_GND4")
		(2 "B.Cu" signal "BOTTOM")
		(9 "F.Adhes" user "F.Adhesive")
		(11 "B.Adhes" user "B.Adhesive")
		(13 "F.Paste" user "Package Geometry/Pastemask Top")
		(15 "B.Paste" user "Package Geometry/Pastemask Bottom")
		(5 "F.SilkS" user "Ref Des/Silkscreen Top")
		(7 "B.SilkS" user "Ref Des/Silkscreen Bottom")
		(1 "F.Mask" user "Board Geometry/Soldermask Top")
		(3 "B.Mask" user "Board Geometry/Soldermask Bottom")
		(17 "Dwgs.User" user "User.Drawings")
		(19 "Cmts.User" user "User.Comments")
		(21 "Eco1.User" user "User.Eco1")
		(23 "Eco2.User" user "User.Eco2")
		(25 "Edge.Cuts" user "Board Geometry/Outline")
		(27 "Margin" user)
		(31 "F.CrtYd" user "Package Geometry/Place Bound Top")
		(29 "B.CrtYd" user "Package Geometry/Place Bound Bottom")
		(35 "F.Fab" user "Ref Des/Assembly Top")
		(33 "B.Fab" user "Ref Des/Assembly Bottom")
	)
	(footprint ""
		(layer "B.Cu")
		(at 20.2946 -18.5928 90)
		(property "Reference" "R2"
			(at -0.1778 -1.15697 270)
			(unlocked yes)
			(layer "B.SilkS")
			(effects
				(font
					(size 0.7874 0.5842)
					(thickness 0.1524)
				)
				(justify mirror)
			)
		)
		(property "Value" "VAL*"
			(at -0.02032 2.13233 90)
			(unlocked yes)
			(layer "B.Fab")
			(hide yes)
			(effects
				(font
					(size 0.7874 0.5842)
					(thickness 0.1524)
				)
				(justify mirror)
			)
		)
		(property "Device Type" "RESISTOR-G155-13300-01,330OHM,A"
			(at -0.008382 1.210564 90)
			(unlocked yes)
			(layer "B.Fab")
			(hide yes)
			(effects
				(font
					(size 0.7874 0.5842)
					(thickness 0.1524)
				)
				(justify mirror)
			)
		)
		(property "User Part Number" "PARTNUM*"
			(at -0.02032 4.024884 90)
			(unlocked yes)
			(layer "Cmts.User")
			(hide yes)
			(effects
				(font
					(size 0.7874 0.5842)
					(thickness 0.1524)
				)
				(justify mirror)
			)
		)
		(property "Tolerance" "TOL*"
			(at -0.044704 3.05435 90)
			(unlocked yes)
			(layer "Cmts.User")
			(hide yes)
			(effects
				(font
					(size 0.7874 0.5842)
					(thickness 0.1524)
				)
				(justify mirror)
			)
		)
		(duplicate_pad_numbers_are_jumpers no)
		(fp_line
			(start 1.143 -0.5588)
			(end 1.143 0.5588)
			(stroke
				(width 0.1)
				(type default)
			)
			(layer "B.SilkS")
		)
		(fp_line
			(start -1.143 -0.5588)
			(end 1.143 -0.5588)
			(stroke
				(width 0.1)
				(type default)
			)
			(layer "B.SilkS")
		)
		(fp_line
			(start 1.143 0.5588)
			(end -1.143 0.5588)
			(stroke
				(width 0.1)
				(type default)
			)
			(layer "B.SilkS")
		)
		(fp_line
			(start -1.143 0.5588)
			(end -1.143 -0.5588)
			(stroke
				(width 0.1)
				(type default)
			)
			(layer "B.SilkS")
		)
		(fp_rect
			(start 1.143 -0.5588)
			(end -1.143 0.5588)
			(stroke
				(width 0)
				(type default)
			)
			(fill no)
			(layer "B.CrtYd")
		)
		(fp_line
			(start 0.508 -0.3048)
			(end 0.508 0.3048)
			(stroke
				(width 0.1)
				(type default)
			)
			(layer "B.Fab")
		)
		(fp_line
			(start -0.508 -0.3048)
			(end 0.508 -0.3048)
			(stroke
				(width 0.1)
				(type default)
			)
			(layer "B.Fab")
		)
		(fp_line
			(start 0.508 0.3048)
			(end -0.508 0.3048)
			(stroke
				(width 0.1)
				(type default)
			)
			(layer "B.Fab")
		)
		(fp_line
			(start -0.508 0.3048)
			(end -0.508 -0.3048)
			(stroke
				(width 0.1)
				(type default)
			)
			(layer "B.Fab")
		)
		(pad "1" smd rect
			(at 0.5334 0 270)
			(size 0.7112 0.6096)
			(layers "B.Cu" "B.Mask" "B.Paste")
			(net "FPGA_OUT_SEC_EEPROM_WP")
		)
		(pad "2" smd rect
			(at -0.5334 0 270)
			(size 0.7112 0.6096)
			(layers "B.Cu" "B.Mask" "B.Paste")
			(net "SEC_EEPROM_WP")
		)
		(zone
			(layer "B.Cu")
			(hatch none 0.5)
			(connect_pads
				(clearance 0)
			)
			(min_thickness 0.25)
			(keepout
				(tracks allowed)
				(vias not_allowed)
				(pads allowed)
				(copperpour not_allowed)
				(footprints allowed)
			)
			(placement
				(enabled no)
				(sheetname "")
			)
			(fill
				(thermal_gap 0.5)
				(thermal_bridge_width 0.5)
				(island_removal_mode 0)
			)
			(polygon
				(pts
					(xy 19.9898 -18.669) (xy 19.9898 -18.5166) (xy 20.5994 -18.5166) (xy 20.5994 -18.669)
				)
			)
		)
	)
	(footprint ""
		(layer "B.Cu")
		(at 85.471 -104.013)
		(property "Reference" "R37"
			(at 0 1.30937 0)
			(unlocked yes)
			(layer "B.SilkS")
			(effects
				(font
					(size 0.7874 0.5842)
					(thickness 0.1524)
				)
				(justify mirror)
			)
		)
		(property "Value" "VAL*"
			(at -0.02032 2.13233 0)
			(unlocked yes)
			(layer "B.Fab")
			(hide yes)
			(effects
				(font
					(size 0.7874 0.5842)
					(thickness 0.1524)
				)
				(justify mirror)
			)
		)
		(property "Tolerance" "TOL*"
			(at -0.044704 3.05435 0)
			(unlocked yes)
			(layer "Cmts.User")
			(hide yes)
			(effects
				(font
					(size 0.7874 0.5842)
					(thickness 0.1524)
				)
				(justify mirror)
			)
		)
		(property "User Part Number" "PARTNUM*"
			(at -0.02032 4.024884 0)
			(unlocked yes)
			(layer "Cmts.User")
			(hide yes)
			(effects
				(font
					(size 0.7874 0.5842)
					(thickness 0.1524)
				)
				(justify mirror)
			)
		)
		(property "Device Type" "RESISTOR-G155-100R0-J0,0OHM,-"
			(at -0.008382 1.210564 0)
			(unlocked yes)
			(layer "B.Fab")
			(hide yes)
			(effects
				(font
					(size 0.7874 0.5842)
					(thickness 0.1524)
				)
				(justify mirror)
			)
		)
		(duplicate_pad_numbers_are_jumpers no)
		(fp_line
			(start -1.143 -0.5588)
			(end 1.143 -0.5588)
			(stroke
				(width 0.1)
				(type default)
			)
			(layer "B.SilkS")
		)
		(fp_line
			(start -1.143 0.5588)
			(end -1.143 -0.5588)
			(stroke
				(width 0.1)
				(type default)
			)
			(layer "B.SilkS")
		)
		(fp_line
			(start 1.143 -0.5588)
			(end 1.143 0.5588)
			(stroke
				(width 0.1)
				(type default)
			)
			(layer "B.SilkS")
		)
		(fp_line
			(start 1.143 0.5588)
			(end -1.143 0.5588)
			(stroke
				(width 0.1)
				(type default)
			)
			(layer "B.SilkS")
		)
		(fp_poly
			(pts
				(xy 1.143 0.5588) (xy -1.143 0.5588) (xy -1.143 -0.5588) (xy 1.143 -0.5588)
			)
			(stroke
				(width 0)
				(type default)
			)
			(fill no)
			(layer "B.CrtYd")
		)
		(fp_line
			(start -0.508 -0.3048)
			(end 0.508 -0.3048)
			(stroke
				(width 0.1)
				(type default)
			)
			(layer "B.Fab")
		)
		(fp_line
			(start -0.508 0.3048)
			(end -0.508 -0.3048)
			(stroke
				(width 0.1)
				(type default)
			)
			(layer "B.Fab")
		)
		(fp_line
			(start 0.508 -0.3048)
			(end 0.508 0.3048)
			(stroke
				(width 0.1)
				(type default)
			)
			(layer "B.Fab")
		)
		(fp_line
			(start 0.508 0.3048)
			(end -0.508 0.3048)
			(stroke
				(width 0.1)
				(type default)
			)
			(layer "B.Fab")
		)
		(pad "1" smd rect
			(at 0.5334 0 180)
			(size 0.7112 0.6096)
			(layers "B.Cu" "B.Mask" "B.Paste")
			(net "XP3R3V_BT")
		)
		(pad "2" smd rect
			(at -0.5334 0 180)
			(size 0.7112 0.6096)
			(layers "B.Cu" "B.Mask" "B.Paste")
			(net "UNNAMED_517_CAPACITOR_I27_1")
		)
		(zone
			(layer "B.Cu")
			(hatch none 0.5)
			(connect_pads
				(clearance 0)
			)
			(min_thickness 0.25)
			(keepout
				(tracks allowed)
				(vias not_allowed)
				(pads allowed)
				(copperpour not_allowed)
				(footprints allowed)
			)
			(placement
				(enabled no)
				(sheetname "")
			)
			(fill
				(thermal_gap 0.5)
				(thermal_bridge_width 0.5)
				(island_removal_mode 0)
			)
			(polygon
				(pts
					(xy 85.5472 -103.7082) (xy 85.5472 -104.3178) (xy 85.3948 -104.3178) (xy 85.3948 -103.7082)
				)
			)
		)
		(zone
			(layer "B.Cu")
			(hatch none 0.5)
			(connect_pads
				(clearance 0)
			)
			(min_thickness 0.25)
			(keepout
				(tracks not_allowed)
				(vias allowed)
				(pads allowed)
				(copperpour not_allowed)
				(footprints allowed)
			)
			(placement
				(enabled no)
				(sheetname "")
			)
			(fill
				(thermal_gap 0.5)
				(thermal_bridge_width 0.5)
				(island_removal_mode 0)
			)
			(polygon
				(pts
					(xy 85.5472 -103.7082) (xy 85.5472 -104.3178) (xy 85.3948 -104.3178) (xy 85.3948 -103.7082)
				)
			)
		)
	)
)
